FILE_TYPE = CONNECTIVITY;
{Allegro Design Entry HDL 17.4-2019 S026 (4007227) 1/17/2022}
"PAGE_NUMBER" = 478;
0"NC";
1"GND\g";
2"GND\g";
3"P12V_AUX\g";
4"GND\g";
5"GND\g";
6"GND\g";
7"GND\g";
8"GND\g";
9"GND\g";
10"GND\g";
11"GND\g";
12"GND\g";
13"GND\g";
14"GND\g";
15"GND\g";
16"GND\g";
17"P5V_AUX\g";
18"GND\g";
19"GND\g";
20"GND\g";
21"P3V3_AUX\g";
22"GND\g";
23"GND\g";
24"GND\g";
25"GND\g";
26"GND\g";
27"GND\g";
28"GND\g";
29"GND\g";
30"GND\g";
31"GND\g";
32"GND\g";
33"SW_P12V_AUX_P0V9_RETIMER_CPU1_FLT\g";
34"P0V9_RETIMER_CPU1_PVCC\g";
35"GND\g";
36"P0V9_RETIMER_CPU1_PVCC\g";
37"GND\g";
38"SW_P12V_AUX_P0V9_RETIMER_CPU1_FLT\g";
39"GND\g";
40"P0V9_CPU1_RT_2D\g";
41"GND\g";
42"P0V9_CPU1_RT_2D\g";
43"P0V9_RETIMER_CPU1_IMON1";
44"SW_P0V9_RETIMER_CPU1_PH1";
45"SW_P0V9_RETIMER_CPU1_BOOT1_RC";
46"P0V9_RETIMER_CPU1_VCC1";
47"SW_P0V9_RETIMER_CPU1_BOOT1";
48"NC_PV09_RETIMER_CPU1_GL2_1";
49"P0V9_RETIMER_CPU1_LSET2";
50"P0V9_RETIMER_CPU1_TEMP0";
51"P0V9_RETIMER_CPU1_PWM2";
52"SW_P0V9_RETIMER_CPU1_PH2";
53"P0V9_RETIMER_CPU1_VOS2";
54"NC_PV09_RETIMER_CPU1_DNC2";
55"PV09_RETIMER_CPU1_VCCS";
56"P0V9_RETIMER_CPU1_IMON2";
57"P0V9_RETIMER_CPU1_VCC2";
58"P0V9_RETIMER_CPU1_VOS1";
59"SW_P0V9_RETIMER_CPU1_SW1_RC";
60"P0V9_RETIMER_CPU1_LSET1";
61"P0V9_RETIMER_CPU1_TEMP0";
62"PV09_RETIMER_CPU1_VCCS";
63"SW_P0V9_RETIMER_CPU1_SW2_RC";
64"NC_PV09_RETIMER_CPU1_DNC1";
65"P0V9_RETIMER_CPU1_PWM1";
66"NC_PV09_RETIMER_CPU1_GL1_1";
67"SW_P0V9_RETIMER_CPU1_SW1";
68"NC_PV09_RETIMER_CPU1_GL2_2";
69"NC_PV09_RETIMER_CPU1_GL1_2";
70"SW_P0V9_RETIMER_CPU1_SW2";
71"SW_P0V9_RETIMER_CPU1_BOOT2_RC";
72"SW_P0V9_RETIMER_CPU1_BOOT2";
%"UNIVERSAL_GND"
"1","(-9500,825)","0","pure_quanta_power","I1";
;
HDL_POWER"GND"
CDS_LIB"pure_quanta_power";
"A"1;
%"Q_CAP"
"1","(-8750,1875)","0","pure_quanta","I10";
;
LOCATION"PC6645"
$SEC"1"
CDS_SEC"1"
MATERIAL"X6S"
PACK_TYPE"C0402"
VOLTAGE"10V"
VALUE"2.2UF"
PART_NUMBER"CH5222KEB01"
CDS_LIB"pure_quanta"
TOLERANCE"10%"
BOM_COST"VR_DIMM ";
"B"
$PN"2"31;
"A"
$PN"1"57;
%"Q_CAP"
"1","(-2775,5100)","0","pure_quanta","I100";
;
LOCATION"PC6819"
$SEC"1"
CDS_SEC"1"
VOLTAGE"16V"
PACK_TYPE"C0805"
MATERIAL"X6S"
TOLERANCE"20%"
VALUE"22UF"
PART_NUMBER"CH6223MEA01"
CDS_LIB"pure_quanta";
"B"
$PN"2"32;
"A"
$PN"1"33;
%"UNIVERSAL_GND"
"1","(-2375,4850)","0","pure_quanta_power","I101";
;
HDL_POWER"GND"
CDS_LIB"pure_quanta_power";
"A"2;
%"Q_CAPP"
"1","(-2375,5125)","0","pure_quanta","I102";
;
LOCATION"PC6619"
$SEC"1"
CDS_SEC"1"
PACK_TYPE"SMLF"
MATERIAL"OSCON"
VOLTAGE"16V"
VALUE"100UF"
TOLERANCE"20%"
PART_NUMBER"CC71003MZ30"
CDS_LIB"pure_quanta";
"A"
$PN"1"33;
"B"
$PN"2"2;
%"VCC15"
"1","(-2425,5550)","0","pure_quanta_power","I103";
;
HDL_POWER"SW_P12V_AUX_P0V9_RETIMER_CPU1_FLT"
CDS_LIB"pure_quanta_power"
BOM_COST"VR_DIMM ";
"A"33;
%"Q_INDUCTOR"
"1","(-1825,5350)","0","pure_quanta","I104";
;
LOCATION"PL6510"
$SEC"1"
CDS_SEC"1"
MATERIAL"IND"
PACK_TYPE"SMLF"
VALUE"100NH/16A"
PART_NUMBER"CV+10G0MZ04"
CDS_LIB"pure_quanta"
NEEDS_NO_SIZE"TRUE";
"1"
$PN"1"33;
"2"
$PN"2"3;
%"UNIVERSAL_POWER"
"1","(-950,5575)","0","pure_quanta_power","I105";
;
HDL_POWER"P12V_AUX"
BOM_COST"VR_DIMM "
CDS_LIB"pure_quanta_power";
"A"3;
%"Q_RES"
"2","(-5425,3625)","0","pure_quanta","I106";
;
LOCATION"PR6624"
$SEC"1"
CDS_SEC"1"
VALUE"1.5"
PACK_TYPE"0402LF"
TOLERANCE"1%"
WATTAGE"1/8W"
MATERIAL"EMPTY"
PART_NUMBER"CS-1504FB00"
CDS_LIB"pure_quanta";
"A"
$PN"1"59;
"B"
$PN"2"4;
%"UNIVERSAL_GND"
"1","(-5425,3400)","0","pure_quanta_power","I107";
;
HDL_POWER"GND"
CDS_LIB"pure_quanta_power";
"A"4;
%"Q_CAP"
"1","(-5425,4150)","0","pure_quanta","I108";
;
LOCATION"PC6622"
$SEC"1"
CDS_SEC"1"
TOLERANCE"10%"
MATERIAL"EMPTY"
PACK_TYPE"C0402"
VALUE"560PF"
VOLTAGE"50V"
PART_NUMBER"CH1566K1B09"
CDS_LIB"pure_quanta";
"B"
$PN"2"59;
"A"
$PN"1"67;
%"Q_CAP"
"1","(-5400,1250)","0","pure_quanta","I109";
;
LOCATION"PC6641"
$SEC"1"
CDS_SEC"1"
VALUE"560PF"
VOLTAGE"50V"
TOLERANCE"10%"
MATERIAL"EMPTY"
PACK_TYPE"C0402"
PART_NUMBER"CH1566K1B09"
CDS_LIB"pure_quanta";
"B"
$PN"2"63;
"A"
$PN"1"70;
%"Q_RES"
"2","(-8750,2400)","0","pure_quanta","I11";
;
LOCATION"PR6627"
$SEC"1"
CDS_SEC"1"
WATTAGE"1/16W"
MATERIAL"CHIP"
PACK_TYPE"0402LF"
TOLERANCE"5%"
VALUE"2.2"
PART_NUMBER"TMP_QCS-2202JB25"
CDS_LIB"pure_quanta"
BOM_COST"VR_DIMM ";
"A"
$PN"1"36;
"B"
$PN"2"57;
%"Q_RES"
"2","(-5400,725)","0","pure_quanta","I110";
;
LOCATION"PR6630"
$SEC"1"
CDS_SEC"1"
MATERIAL"EMPTY"
PACK_TYPE"0402LF"
TOLERANCE"1%"
WATTAGE"1/8W"
VALUE"1.5"
PART_NUMBER"CS-1504FB00"
CDS_LIB"pure_quanta";
"A"
$PN"1"63;
"B"
$PN"2"5;
%"UNIVERSAL_GND"
"1","(-5400,500)","0","pure_quanta_power","I111";
;
HDL_POWER"GND"
CDS_LIB"pure_quanta_power";
"A"5;
%"UNIVERSAL_POWER"
"1","(-8350,5675)","0","pure_quanta_power","I112";
;
HDL_POWER"P0V9_RETIMER_CPU1_PVCC"
CDS_LIB"pure_quanta_power";
"A"34;
%"UNIVERSAL_GND"
"1","(-950,4800)","0","pure_quanta_power","I113";
;
HDL_POWER"GND"
CDS_LIB"pure_quanta_power";
"A"6;
%"Q_CAP"
"1","(-950,5125)","0","pure_quanta","I114";
;
LOCATION"PC6620"
$SEC"1"
CDS_SEC"1"
VOLTAGE"25V"
TOLERANCE"10%"
MATERIAL"X7R"
VALUE"0.1UF"
PACK_TYPE"0402"
PART_NUMBER"CH4104K1B00"
CDS_LIB"pure_quanta";
"B"
$PN"2"6;
"A"
$PN"1"3;
%"ISL99390FRZTR5935"
"1","(-6950,1450)","0","pure_quanta","I12";
;
LOCATION"PU6512"
SEC"1"
VALUE"ISL99390FRZ-TR5935"
MATERIAL"IC"
PART_TYPE"SMLF"
PART_NUMBER"AL099390004"
SEC_TYPE""
CDS_LIB"pure_quanta"
CDS_LMAN_SYM_OUTLINE"-300,700,250,-650"
NEEDS_NO_SIZE"TRUE"
BOM_COST"VR_DIMM ";
"PGND2"
$PN"7_9-20_24"35;
"GL2"
$PN"41"68;
"GL1"
$PN"6"69;
"DNC"
$PN"31"54;
"EN"
$PN"35"57;
"PGND3"
$PN"40"35;
"VOS"
$PN"1"53;
"VIN2"
$PN"30"38;
"PGND1"
$PN"5"35;
"SW"
$PN"10_19"70;
"LSET"
$PN"37"49;
"IOUT"
$PN"38"56;
"TOUT_FLT"
$PN"36"50;
"PVCC"
$PN"4"36;
"PHASE"
$PN"32"52;
"VIN1"
$PN"25_29"38;
"BOOT"
$PN"33"72;
"AGND"
$PN"2"35;
"VCC"
$PN"3"57;
"REFIN"
$PN"39"55;
"PWM"
$PN"34"51;
%"UNIVERSAL_GND"
"1","(-8050,2150)","0","pure_quanta_power","I13";
;
HDL_POWER"GND"
CDS_LIB"pure_quanta_power";
"A"7;
%"Q_CAP"
"1","(-8050,2400)","0","pure_quanta","I14";
;
LOCATION"PC6644_09P1_2"
$SEC"1"
CDS_SEC"1"
TOLERANCE"10%"
VOLTAGE"10V"
PACK_TYPE"C0402"
VALUE"2.2UF"
MATERIAL"X6S"
PART_NUMBER"CH5222KEB01"
CDS_LIB"pure_quanta"
BOM_COST"VR_DIMM ";
"B"
$PN"2"7;
"A"
$PN"1"36;
%"UNIVERSAL_GND"
"1","(-6375,650)","0","pure_quanta_power","I15";
;
HDL_POWER"GND"
CDS_LIB"pure_quanta_power";
"A"35;
%"Q_RES"
"1","(-5025,375)","0","pure_quanta","I16";
;
LOCATION"PR6631"
$SEC"1"
CDS_SEC"1"
PACK_TYPE"0402LF"
WATTAGE"1/16W"
TOLERANCE"5%"
MATERIAL"CHIP"
VALUE"0"
PART_NUMBER"CS00002JB13"
BOM_COST"VR_DIMM "
CDS_LIB"pure_quanta";
"B"
$PN"2"40;
"A"
$PN"1"53;
%"UNIVERSAL_GND"
"1","(-5850,1975)","0","pure_quanta_power","I17";
;
HDL_POWER"GND"
CDS_LIB"pure_quanta_power";
"A"8;
%"Q_CAP"
"1","(-5850,2250)","0","pure_quanta","I18";
;
LOCATION"PC6634_2"
$SEC"1"
CDS_SEC"1"
PACK_TYPE"0402"
MATERIAL"X7R"
VALUE"3300PF"
TOLERANCE"10%"
VOLTAGE"50V"
PART_NUMBER"TMP_QCH2336K1B12"
CDS_LIB"pure_quanta"
BOM_COST"VR_DIMM ";
"B"
$PN"2"8;
"A"
$PN"1"38;
%"Q_RES"
"1","(-5350,1800)","0","pure_quanta","I19";
;
LOCATION"PR6629"
$SEC"1"
CDS_SEC"1"
VALUE"5.6"
MATERIAL"CHIP"
PACK_TYPE"0402LF"
TOLERANCE"1%"
WATTAGE"1/16W"
PART_NUMBER"CS-5602FB01"
CDS_LIB"pure_quanta";
"B"
$PN"2"71;
"A"
$PN"1"72;
%"Q_CAP"
"1","(-9500,1025)","0","pure_quanta","I2";
;
LOCATION"PC6646"
$SEC"1"
CDS_SEC"1"
PACK_TYPE"C0402"
VOLTAGE"50V"
VALUE"100NF"
TOLERANCE"10%"
MATERIAL"X7R"
PART_NUMBER"CH4106K1B01"
CDS_LIB"pure_quanta"
BOM_COST"VR_CPU";
"B"
$PN"2"1;
"A"
$PN"1"55;
%"UNIVERSAL_GND"
"1","(-5350,1975)","0","pure_quanta_power","I20";
;
HDL_POWER"GND"
CDS_LIB"pure_quanta_power";
"A"9;
%"Q_CAP"
"1","(-5350,2250)","0","pure_quanta","I21";
;
LOCATION"PC6633_2"
$SEC"1"
CDS_SEC"1"
VALUE"1UF"
MATERIAL"X6S"
PACK_TYPE"C0402"
TOLERANCE"10%"
VOLTAGE"25V"
PART_NUMBER"CH5104KEB02"
CDS_LIB"pure_quanta"
BOM_COST"VR_DIMM ";
"B"
$PN"2"9;
"A"
$PN"1"38;
%"Q_INDUCTOR"
"1","(-4775,1475)","0","pure_quanta","I22";
;
LOCATION"PL6512"
$SEC"1"
CDS_SEC"1"
VALUE"120NH/69A"
PACK_TYPE"SMLF"
MATERIAL"IND"
PART_NUMBER"CV+12^0EZ03"
CDS_LIB"pure_quanta"
NEEDS_NO_SIZE"TRUE"
BOM_COST"VR_DIMM ";
"1"
$PN"1"70;
"2"
$PN"2"40;
%"Q_CAP"
"1","(-4000,1300)","0","pure_quanta","I23";
;
LOCATION"PC6807"
$SEC"1"
CDS_SEC"1"
TOLERANCE"10%"
MATERIAL"X7R"
PACK_TYPE"C0402"
VOLTAGE"50V"
VALUE"100NF"
PART_NUMBER"CH4106K1B01"
BOM_COST"VR_DIMM "
CDS_LIB"pure_quanta";
"B"
$PN"2"39;
"A"
$PN"1"40;
%"UNIVERSAL_GND"
"1","(-4850,1975)","0","pure_quanta_power","I24";
;
HDL_POWER"GND"
CDS_LIB"pure_quanta_power";
"A"10;
%"Q_CAP"
"1","(-4850,2250)","0","pure_quanta","I25";
;
LOCATION"PC6635_2"
$SEC"1"
CDS_SEC"1"
PACK_TYPE"C0805"
MATERIAL"X6S"
TOLERANCE"20%"
VALUE"22UF"
VOLTAGE"16V"
PART_NUMBER"CH6223MEA01"
CDS_LIB"pure_quanta"
REUSE_ID"41"
BOM_COST"VR_DIMM ";
"B"
$PN"2"10;
"A"
$PN"1"38;
%"Q_CAP"
"2","(-3975,1800)","0","pure_quanta","I26";
;
LOCATION"PC6640"
$SEC"1"
CDS_SEC"1"
MATERIAL"X7R"
TOLERANCE"10%"
VOLTAGE"50V"
VALUE"100NF"
PACK_TYPE"C0402"
PART_NUMBER"CH4106K1B01"
CDS_LIB"pure_quanta"
BOM_COST"VR_DIMM "
REUSE_ID"55";
"A"
$PN"1"71;
"B"
$PN"2"52;
%"UNIVERSAL_GND"
"1","(-4350,1975)","0","pure_quanta_power","I27";
;
HDL_POWER"GND"
CDS_LIB"pure_quanta_power";
"A"11;
%"Q_CAP"
"1","(-4350,2250)","0","pure_quanta","I28";
;
LOCATION"PC6636_2"
$SEC"1"
CDS_SEC"1"
PACK_TYPE"C0805"
TOLERANCE"20%"
MATERIAL"X6S"
VALUE"22UF"
VOLTAGE"16V"
PART_NUMBER"CH6223MEA01"
CDS_LIB"pure_quanta"
REUSE_ID"41"
BOM_COST"VR_DIMM ";
"B"
$PN"2"11;
"A"
$PN"1"38;
%"Q_CAP"
"1","(-3675,1300)","0","pure_quanta","I29";
;
LOCATION"PC6642_2"
$SEC"1"
CDS_SEC"1"
PACK_TYPE"C0805"
VOLTAGE"4V"
VALUE"22UF"
MATERIAL"X6S"
TOLERANCE"20%"
PART_NUMBER"CH622KMEA03"
CDS_LIB"pure_quanta";
"B"
$PN"2"39;
"A"
$PN"1"40;
%"Q_CAP"
"1","(-3450,1300)","0","pure_quanta","I30";
;
LOCATION"PC6643_2"
$SEC"1"
CDS_SEC"1"
VOLTAGE"4V"
MATERIAL"X6S"
PACK_TYPE"C0805"
VALUE"22UF"
TOLERANCE"20%"
PART_NUMBER"CH622KMEA03"
CDS_LIB"pure_quanta";
"B"
$PN"2"39;
"A"
$PN"1"40;
%"Q_CAPP"
"1","(-3225,1300)","0","pure_quanta","I31";
;
LOCATION"PC6813"
$SEC"1"
CDS_SEC"1"
MATERIAL"SPCAP"
VOLTAGE"2.5V"
PACK_TYPE"SMLF"
TOLERANCE"20%"
VALUE"470UF"
PART_NUMBER"CH747LM8818"
CDS_LIB"pure_quanta";
"A"
$PN"1"40;
"B"
$PN"2"39;
%"Q_CAPP"
"1","(-3000,1300)","0","pure_quanta","I32";
;
LOCATION"PC6814"
$SEC"1"
CDS_SEC"1"
MATERIAL"SPCAP"
VOLTAGE"2.5V"
VALUE"470UF"
PACK_TYPE"SMLF"
TOLERANCE"20%"
PART_NUMBER"CH747LM8818"
CDS_LIB"pure_quanta";
"A"
$PN"1"40;
"B"
$PN"2"39;
%"UNIVERSAL_GND"
"1","(-3875,1975)","0","pure_quanta_power","I33";
;
HDL_POWER"GND"
CDS_LIB"pure_quanta_power";
"A"12;
%"UNIVERSAL_GND"
"1","(-3500,1975)","0","pure_quanta_power","I34";
;
HDL_POWER"GND"
CDS_LIB"pure_quanta_power";
"A"13;
%"Q_CAP"
"1","(-3875,2250)","0","pure_quanta","I35";
;
LOCATION"PC6637_2"
$SEC"1"
CDS_SEC"1"
PACK_TYPE"C0805"
TOLERANCE"20%"
VALUE"22UF"
VOLTAGE"16V"
MATERIAL"X6S"
PART_NUMBER"CH6223MEA01"
CDS_LIB"pure_quanta"
BOM_COST"VR_DIMM "
REUSE_ID"41";
"B"
$PN"2"12;
"A"
$PN"1"38;
%"Q_CAP"
"1","(-3500,2250)","0","pure_quanta","I36";
;
LOCATION"PC6638_2"
$SEC"1"
CDS_SEC"1"
TOLERANCE"20%"
MATERIAL"X6S"
PACK_TYPE"C0805"
VOLTAGE"16V"
VALUE"22UF"
PART_NUMBER"CH6223MEA01"
CDS_LIB"pure_quanta"
REUSE_ID"41"
BOM_COST"VR_DIMM ";
"B"
$PN"2"13;
"A"
$PN"1"38;
%"UNIVERSAL_GND"
"1","(-3100,1975)","0","pure_quanta_power","I37";
;
HDL_POWER"GND"
CDS_LIB"pure_quanta_power";
"A"14;
%"Q_CAP"
"1","(-3100,2200)","0","pure_quanta","I38";
;
LOCATION"PC6639"
$SEC"1"
CDS_SEC"1"
TOLERANCE"20%"
MATERIAL"X6S"
PACK_TYPE"C0805"
VOLTAGE"16V"
VALUE"22UF"
PART_NUMBER"CH6223MEA01"
CDS_LIB"pure_quanta";
"B"
$PN"2"14;
"A"
$PN"1"38;
%"Q_CAP"
"1","(-9625,3925)","0","pure_quanta","I39";
;
LOCATION"PC6611_1"
$SEC"1"
CDS_SEC"1"
VOLTAGE"50V"
TOLERANCE"10%"
VALUE"100NF"
MATERIAL"X7R"
PACK_TYPE"C0402"
PART_NUMBER"CH4106K1B01"
CDS_LIB"pure_quanta"
BOM_COST"VR_CPU";
"B"
$PN"2"16;
"A"
$PN"1"62;
%"UNIVERSAL_GND"
"1","(-8700,650)","0","pure_quanta_power","I4";
;
HDL_POWER"GND"
CDS_LIB"pure_quanta_power";
"A"15;
%"UNIVERSAL_GND"
"1","(-9625,3725)","0","pure_quanta_power","I40";
;
HDL_POWER"GND"
CDS_LIB"pure_quanta_power";
"A"16;
%"Q_RES"
"2","(-9425,6150)","0","pure_quanta","I42";
;
LOCATION"PR6619"
$SEC"1"
CDS_SEC"1"
WATTAGE"1/16W"
MATERIAL"CHIP"
PACK_TYPE"0402LF"
VALUE"0"
TOLERANCE"5%"
PART_NUMBER"CS00002JB13"
CDS_LIB"pure_quanta";
"A"
$PN"1"17;
"B"
$PN"2"34;
%"UNIVERSAL_POWER"
"1","(-9425,6450)","0","pure_quanta_power","I43";
;
HDL_POWER"P5V_AUX"
CDS_LIB"pure_quanta_power";
"A"17;
%"UNIVERSAL_POWER"
"1","(-8750,3050)","0","pure_quanta_power","I44";
;
HDL_POWER"P0V9_RETIMER_CPU1_PVCC"
CDS_LIB"pure_quanta_power";
"A"36;
%"UNIVERSAL_GND"
"1","(-8825,3550)","0","pure_quanta_power","I45";
;
HDL_POWER"GND"
CDS_LIB"pure_quanta_power";
"A"18;
%"Q_RES"
"2","(-8825,3800)","0","pure_quanta","I46";
;
LOCATION"PR6622"
$SEC"1"
CDS_SEC"1"
PACK_TYPE"0402LF"
WATTAGE"1/16W"
VALUE"8.87K"
MATERIAL"EMPTY"
TOLERANCE"1%"
PART_NUMBER"CS28872FB01"
CDS_LIB"pure_quanta";
"A"
$PN"1"60;
"B"
$PN"2"18;
%"UNIVERSAL_GND"
"1","(-8875,4575)","0","pure_quanta_power","I48";
;
HDL_POWER"GND"
CDS_LIB"pure_quanta_power";
"A"19;
%"Q_RES"
"2","(-8700,900)","0","pure_quanta","I5";
;
LOCATION"PR6628"
$SEC"1"
CDS_SEC"1"
WATTAGE"1/16W"
TOLERANCE"1%"
VALUE"8.87K"
MATERIAL"EMPTY"
PACK_TYPE"0402LF"
PART_NUMBER"CS28872FB01"
CDS_LIB"pure_quanta";
"A"
$PN"1"49;
"B"
$PN"2"15;
%"ISL99390FRZTR5935"
"1","(-7075,4350)","0","pure_quanta","I51";
;
LOCATION"PU6511"
SEC"1"
VALUE"ISL99390FRZ-TR5935"
MATERIAL"IC"
PART_TYPE"SMLF"
PART_NUMBER"AL099390004"
SEC_TYPE""
CDS_LIB"pure_quanta"
CDS_LMAN_SYM_OUTLINE"-300,700,250,-650"
NEEDS_NO_SIZE"TRUE"
BOM_COST"VR_DIMM ";
"PGND2"
$PN"7_9-20_24"37;
"GL2"
$PN"41"48;
"GL1"
$PN"6"66;
"DNC"
$PN"31"64;
"EN"
$PN"35"46;
"PGND3"
$PN"40"37;
"VOS"
$PN"1"58;
"VIN2"
$PN"30"33;
"PGND1"
$PN"5"37;
"SW"
$PN"10_19"67;
"LSET"
$PN"37"60;
"IOUT"
$PN"38"43;
"TOUT_FLT"
$PN"36"61;
"PVCC"
$PN"4"34;
"PHASE"
$PN"32"44;
"VIN1"
$PN"25_29"33;
"BOOT"
$PN"33"47;
"AGND"
$PN"2"37;
"VCC"
$PN"3"46;
"REFIN"
$PN"39"62;
"PWM"
$PN"34"65;
%"Q_CAP"
"1","(-8875,4775)","0","pure_quanta","I52";
;
LOCATION"PC6610"
$SEC"1"
CDS_SEC"1"
PACK_TYPE"C0402"
MATERIAL"X6S"
VOLTAGE"10V"
VALUE"2.2UF"
PART_NUMBER"CH5222KEB01"
CDS_LIB"pure_quanta"
TOLERANCE"10%"
BOM_COST"VR_DIMM ";
"B"
$PN"2"19;
"A"
$PN"1"46;
%"Q_RES"
"2","(-8875,5300)","0","pure_quanta","I53";
;
LOCATION"PR6621"
$SEC"1"
CDS_SEC"1"
WATTAGE"1/16W"
VALUE"2.2"
TOLERANCE"5%"
MATERIAL"CHIP"
PACK_TYPE"0402LF"
PART_NUMBER"TMP_QCS-2202JB25"
CDS_LIB"pure_quanta"
BOM_COST"VR_DIMM ";
"A"
$PN"1"34;
"B"
$PN"2"46;
%"UNIVERSAL_GND"
"1","(-8175,5050)","0","pure_quanta_power","I54";
;
HDL_POWER"GND"
CDS_LIB"pure_quanta_power";
"A"20;
%"Q_CAP"
"1","(-8175,5300)","0","pure_quanta","I55";
;
LOCATION"PC6609_09P1_1"
$SEC"1"
CDS_SEC"1"
VOLTAGE"10V"
VALUE"2.2UF"
TOLERANCE"10%"
PACK_TYPE"C0402"
MATERIAL"X6S"
PART_NUMBER"CH5222KEB01"
CDS_LIB"pure_quanta"
BOM_COST"VR_DIMM ";
"B"
$PN"2"20;
"A"
$PN"1"34;
%"Q_RES"
"2","(-8525,6150)","0","pure_quanta","I56";
;
LOCATION"PR6620"
$SEC"1"
CDS_SEC"1"
VALUE"0"
TOLERANCE"5%"
WATTAGE"1/16W"
MATERIAL"EMPTY"
PACK_TYPE"0402LF"
PART_NUMBER"CS00002JB13"
CDS_LIB"pure_quanta";
"A"
$PN"1"21;
"B"
$PN"2"34;
%"UNIVERSAL_POWER"
"1","(-8525,6450)","0","pure_quanta_power","I57";
;
HDL_POWER"P3V3_AUX"
CDS_LIB"pure_quanta_power";
"A"21;
%"UNIVERSAL_GND"
"1","(-6500,3550)","0","pure_quanta_power","I58";
;
HDL_POWER"GND"
CDS_LIB"pure_quanta_power";
"A"37;
%"Q_RES"
"1","(-5100,3200)","0","pure_quanta","I59";
;
LOCATION"PR6626"
$SEC"1"
CDS_SEC"1"
VALUE"0"
TOLERANCE"5%"
PACK_TYPE"0402LF"
WATTAGE"1/16W"
MATERIAL"CHIP"
PART_NUMBER"CS00002JB13"
BOM_COST"VR_DIMM "
CDS_LIB"pure_quanta";
"B"
$PN"2"42;
"A"
$PN"1"58;
%"UNIVERSAL_GND"
"1","(-5975,4875)","0","pure_quanta_power","I60";
;
HDL_POWER"GND"
CDS_LIB"pure_quanta_power";
"A"22;
%"Q_CAP"
"1","(-5975,5150)","0","pure_quanta","I61";
;
LOCATION"PC6613_1"
$SEC"1"
CDS_SEC"1"
PACK_TYPE"0402"
TOLERANCE"10%"
MATERIAL"X7R"
VOLTAGE"50V"
VALUE"3300PF"
PART_NUMBER"TMP_QCH2336K1B12"
CDS_LIB"pure_quanta"
BOM_COST"VR_DIMM ";
"B"
$PN"2"22;
"A"
$PN"1"33;
%"Q_RES"
"1","(-5475,4700)","0","pure_quanta","I62";
;
LOCATION"PR6623"
$SEC"1"
CDS_SEC"1"
VALUE"5.6"
MATERIAL"CHIP"
PACK_TYPE"0402LF"
WATTAGE"1/16W"
TOLERANCE"1%"
PART_NUMBER"CS-5602FB01"
CDS_LIB"pure_quanta";
"B"
$PN"2"45;
"A"
$PN"1"47;
%"UNIVERSAL_GND"
"1","(-5475,4875)","0","pure_quanta_power","I63";
;
HDL_POWER"GND"
CDS_LIB"pure_quanta_power";
"A"23;
%"Q_CAP"
"1","(-5475,5150)","0","pure_quanta","I64";
;
LOCATION"PC6612_1"
$SEC"1"
CDS_SEC"1"
PACK_TYPE"C0402"
VOLTAGE"25V"
TOLERANCE"10%"
VALUE"1UF"
MATERIAL"X6S"
PART_NUMBER"CH5104KEB02"
CDS_LIB"pure_quanta"
BOM_COST"VR_DIMM ";
"B"
$PN"2"23;
"A"
$PN"1"33;
%"Q_INDUCTOR"
"1","(-4900,4375)","0","pure_quanta","I65";
;
LOCATION"PL6511"
$SEC"1"
CDS_SEC"1"
VALUE"120NH/69A"
PACK_TYPE"SMLF"
MATERIAL"IND"
PART_NUMBER"CV+12^0EZ03"
CDS_LIB"pure_quanta"
NEEDS_NO_SIZE"TRUE"
BOM_COST"VR_DIMM ";
"1"
$PN"1"67;
"2"
$PN"2"42;
%"Q_CAP"
"1","(-4125,4200)","0","pure_quanta","I66";
;
LOCATION"PC6623"
$SEC"1"
CDS_SEC"1"
VALUE"100NF"
PACK_TYPE"C0402"
MATERIAL"X7R"
VOLTAGE"50V"
TOLERANCE"10%"
PART_NUMBER"CH4106K1B01"
CDS_LIB"pure_quanta"
BOM_COST"VR_DIMM ";
"B"
$PN"2"41;
"A"
$PN"1"42;
%"Q_CAP"
"1","(-3800,4200)","0","pure_quanta","I67";
;
LOCATION"PC6624_1"
$SEC"1"
CDS_SEC"1"
PACK_TYPE"C0805"
MATERIAL"X6S"
VALUE"22UF"
VOLTAGE"4V"
TOLERANCE"20%"
PART_NUMBER"CH622KMEA03"
CDS_LIB"pure_quanta";
"B"
$PN"2"41;
"A"
$PN"1"42;
%"Q_CAP"
"1","(-3575,4200)","0","pure_quanta","I68";
;
LOCATION"PC6625_1"
$SEC"1"
CDS_SEC"1"
PACK_TYPE"C0805"
MATERIAL"X6S"
VALUE"22UF"
VOLTAGE"4V"
TOLERANCE"20%"
PART_NUMBER"CH622KMEA03"
CDS_LIB"pure_quanta";
"B"
$PN"2"41;
"A"
$PN"1"42;
%"Q_CAPP"
"1","(-3350,4200)","0","pure_quanta","I69";
;
LOCATION"PC6626"
$SEC"1"
CDS_SEC"1"
MATERIAL"SPCAP"
VOLTAGE"2.5V"
VALUE"470UF"
TOLERANCE"20%"
PACK_TYPE"SMLF"
PART_NUMBER"CH747LM8818"
CDS_LIB"pure_quanta";
"A"
$PN"1"42;
"B"
$PN"2"41;
%"Q_CAPP"
"1","(-3125,4200)","0","pure_quanta","I70";
;
LOCATION"PC6627"
$SEC"1"
CDS_SEC"1"
MATERIAL"SPCAP"
VOLTAGE"2.5V"
VALUE"470UF"
PACK_TYPE"SMLF"
TOLERANCE"20%"
PART_NUMBER"CH747LM8818"
CDS_LIB"pure_quanta";
"A"
$PN"1"42;
"B"
$PN"2"41;
%"UNIVERSAL_GND"
"1","(-4975,4875)","0","pure_quanta_power","I71";
;
HDL_POWER"GND"
CDS_LIB"pure_quanta_power";
"A"24;
%"Q_CAP"
"1","(-4975,5150)","0","pure_quanta","I72";
;
LOCATION"PC6614_1"
$SEC"1"
CDS_SEC"1"
PACK_TYPE"C0805"
VOLTAGE"16V"
TOLERANCE"20%"
VALUE"22UF"
MATERIAL"X6S"
PART_NUMBER"CH6223MEA01"
CDS_LIB"pure_quanta"
REUSE_ID"41"
BOM_COST"VR_DIMM ";
"B"
$PN"2"24;
"A"
$PN"1"33;
%"UNIVERSAL_GND"
"1","(-4475,4875)","0","pure_quanta_power","I73";
;
HDL_POWER"GND"
CDS_LIB"pure_quanta_power";
"A"25;
%"Q_CAP"
"1","(-4475,5150)","0","pure_quanta","I74";
;
LOCATION"PC6615_1"
$SEC"1"
CDS_SEC"1"
PACK_TYPE"C0805"
TOLERANCE"20%"
VOLTAGE"16V"
VALUE"22UF"
MATERIAL"X6S"
PART_NUMBER"CH6223MEA01"
CDS_LIB"pure_quanta"
REUSE_ID"41"
BOM_COST"VR_DIMM ";
"B"
$PN"2"25;
"A"
$PN"1"33;
%"UNIVERSAL_GND"
"1","(-4000,4875)","0","pure_quanta_power","I75";
;
HDL_POWER"GND"
CDS_LIB"pure_quanta_power";
"A"26;
%"Q_CAP"
"2","(-4100,4700)","0","pure_quanta","I76";
;
LOCATION"PC6621"
$SEC"1"
CDS_SEC"1"
PACK_TYPE"C0402"
TOLERANCE"10%"
MATERIAL"X7R"
VOLTAGE"50V"
VALUE"100NF"
PART_NUMBER"CH4106K1B01"
CDS_LIB"pure_quanta"
BOM_COST"VR_DIMM "
REUSE_ID"55";
"A"
$PN"1"45;
"B"
$PN"2"44;
%"Q_CAP"
"1","(-4000,5150)","0","pure_quanta","I77";
;
LOCATION"PC6616_1"
$SEC"1"
CDS_SEC"1"
VOLTAGE"16V"
MATERIAL"X6S"
TOLERANCE"20%"
PACK_TYPE"C0805"
VALUE"22UF"
PART_NUMBER"CH6223MEA01"
CDS_LIB"pure_quanta"
BOM_COST"VR_DIMM "
REUSE_ID"41";
"B"
$PN"2"26;
"A"
$PN"1"33;
%"UNIVERSAL_GND"
"1","(-3625,4875)","0","pure_quanta_power","I78";
;
HDL_POWER"GND"
CDS_LIB"pure_quanta_power";
"A"27;
%"Q_CAP"
"1","(-3625,5150)","0","pure_quanta","I79";
;
LOCATION"PC6617_1"
$SEC"1"
CDS_SEC"1"
MATERIAL"X6S"
PACK_TYPE"C0805"
VALUE"22UF"
VOLTAGE"16V"
TOLERANCE"20%"
PART_NUMBER"CH6223MEA01"
CDS_LIB"pure_quanta"
REUSE_ID"41"
BOM_COST"VR_DIMM ";
"B"
$PN"2"27;
"A"
$PN"1"33;
%"Q_CAP"
"1","(-3225,5100)","0","pure_quanta","I80";
;
LOCATION"PC6618"
$SEC"1"
CDS_SEC"1"
PACK_TYPE"C0805"
TOLERANCE"20%"
MATERIAL"X6S"
VALUE"22UF"
VOLTAGE"16V"
PART_NUMBER"CH6223MEA01"
CDS_LIB"pure_quanta";
"B"
$PN"2"28;
"A"
$PN"1"33;
%"UNIVERSAL_GND"
"1","(-3225,4875)","0","pure_quanta_power","I81";
;
HDL_POWER"GND"
CDS_LIB"pure_quanta_power";
"A"28;
%"Q_CAPP"
"1","(-2800,1300)","0","pure_quanta","I82";
;
LOCATION"PC6815"
$SEC"1"
CDS_SEC"1"
MATERIAL"SPCAP"
VOLTAGE"2.5V"
VALUE"470UF"
PACK_TYPE"SMLF"
TOLERANCE"20%"
PART_NUMBER"CH747LM8818"
CDS_LIB"pure_quanta";
"A"
$PN"1"40;
"B"
$PN"2"39;
%"Q_CAPP"
"1","(-2475,1300)","0","pure_quanta","I83";
;
LOCATION"PC6631"
$SEC"1"
CDS_SEC"1"
TOLERANCE"20%"
VALUE"390UF"
VOLTAGE"2.5V"
PACK_TYPE"SMLF"
MATERIAL"ALUM"
PART_NUMBER"CC7390JMZ13"
CDS_LIB"pure_quanta";
"A"
$PN"1"40;
"B"
$PN"2"39;
%"Q_CAPP"
"1","(-2225,1300)","0","pure_quanta","I84";
;
LOCATION"PC6632"
$SEC"1"
CDS_SEC"1"
MATERIAL"ALUM"
PACK_TYPE"SMLF"
VOLTAGE"2.5V"
TOLERANCE"20%"
VALUE"390UF"
PART_NUMBER"CC7390JMZ13"
CDS_LIB"pure_quanta";
"A"
$PN"1"40;
"B"
$PN"2"39;
%"UNIVERSAL_GND"
"1","(-2650,1975)","0","pure_quanta_power","I85";
;
HDL_POWER"GND"
CDS_LIB"pure_quanta_power";
"A"29;
%"Q_CAP"
"1","(-2650,2200)","0","pure_quanta","I86";
;
LOCATION"PC6818"
$SEC"1"
CDS_SEC"1"
MATERIAL"X6S"
PACK_TYPE"C0805"
TOLERANCE"20%"
VOLTAGE"16V"
VALUE"22UF"
PART_NUMBER"CH6223MEA01"
CDS_LIB"pure_quanta";
"B"
$PN"2"29;
"A"
$PN"1"38;
%"UNIVERSAL_GND"
"1","(-2250,1950)","0","pure_quanta_power","I87";
;
HDL_POWER"GND"
CDS_LIB"pure_quanta_power";
"A"30;
%"Q_CAPP"
"1","(-2250,2225)","0","pure_quanta","I88";
;
LOCATION"PC473"
$SEC"1"
CDS_SEC"1"
PACK_TYPE"SMLF"
MATERIAL"OSCON"
TOLERANCE"20%"
VALUE"100UF"
VOLTAGE"16V"
PART_NUMBER"CC71003MZ30"
CDS_LIB"pure_quanta";
"A"
$PN"1"38;
"B"
$PN"2"30;
%"VCC15"
"1","(-2300,2650)","0","pure_quanta_power","I89";
;
HDL_POWER"SW_P12V_AUX_P0V9_RETIMER_CPU1_FLT"
CDS_LIB"pure_quanta_power"
BOM_COST"VR_DIMM ";
"A"38;
%"UNIVERSAL_GND"
"1","(-8750,1675)","0","pure_quanta_power","I9";
;
HDL_POWER"GND"
CDS_LIB"pure_quanta_power";
"A"31;
%"UNIVERSAL_GND"
"1","(-2225,950)","0","pure_quanta_power","I90";
;
HDL_POWER"GND"
CDS_LIB"pure_quanta_power";
"A"39;
%"VCC15"
"1","(-1250,1775)","0","pure_quanta_power","I92";
;
HDL_POWER"P0V9_CPU1_RT_2D"
CDS_LIB"pure_quanta_power"
BOM_COST"VR_DIMM ";
"A"40;
%"Q_CAPP"
"1","(-2925,4200)","0","pure_quanta","I93";
;
LOCATION"PC6628"
$SEC"1"
CDS_SEC"1"
MATERIAL"SPCAP"
VOLTAGE"2.5V"
PACK_TYPE"SMLF"
TOLERANCE"20%"
VALUE"470UF"
PART_NUMBER"CH747LM8818"
CDS_LIB"pure_quanta";
"A"
$PN"1"42;
"B"
$PN"2"41;
%"Q_CAPP"
"1","(-2600,4200)","0","pure_quanta","I94";
;
LOCATION"PC6629"
$SEC"1"
CDS_SEC"1"
TOLERANCE"20%"
PACK_TYPE"SMLF"
VALUE"390UF"
VOLTAGE"2.5V"
MATERIAL"ALUM"
PART_NUMBER"CC7390JMZ13"
CDS_LIB"pure_quanta";
"A"
$PN"1"42;
"B"
$PN"2"41;
%"Q_CAPP"
"1","(-2325,4200)","0","pure_quanta","I95";
;
LOCATION"PC6630"
$SEC"1"
CDS_SEC"1"
TOLERANCE"20%"
PACK_TYPE"SMLF"
VALUE"390UF"
VOLTAGE"2.5V"
MATERIAL"ALUM"
PART_NUMBER"CC7390JMZ13"
CDS_LIB"pure_quanta";
"A"
$PN"1"42;
"B"
$PN"2"41;
%"UNIVERSAL_GND"
"1","(-2000,3875)","0","pure_quanta_power","I96";
;
HDL_POWER"GND"
CDS_LIB"pure_quanta_power";
"A"41;
%"Q_RES"
"2","(-2000,4175)","0","pure_quanta","I97";
;
LOCATION"PR6625"
$SEC"1"
CDS_SEC"1"
PACK_TYPE"0603LF"
VALUE"499"
TOLERANCE"1%"
MATERIAL"CHIP"
WATTAGE"1/10W"
PART_NUMBER"CS14993F901"
CDS_LIB"pure_quanta";
"A"
$PN"1"42;
"B"
$PN"2"41;
%"VCC15"
"1","(-1375,4675)","0","pure_quanta_power","I98";
;
HDL_POWER"P0V9_CPU1_RT_2D"
CDS_LIB"pure_quanta_power"
BOM_COST"VR_DIMM ";
"A"42;
%"UNIVERSAL_GND"
"1","(-2775,4875)","0","pure_quanta_power","I99";
;
HDL_POWER"GND"
CDS_LIB"pure_quanta_power";
"A"32;
END.
